# S9S_MB_2U (Grand Teton) — schematic netlist excerpt (pin names and nets, part order shuffled) for the footprints in the layout excerpt that follows; sources: Cadence DE-HDL packaged netlist, KiCad conversion of 03242023_DA0F0TMBIJ0_F0T_Motherboard_J_brd_V01_OCP.brd

C592  Q_CAP  0.1UF 25V 10% X7R  pkg 0402  page 156 : A = P3V3_AUX ; B = GND

U304  GTL2014PW  IC  pkg TSSOP14  page 225
  DIR  = PD_GTL2014_BMC_JTAG_DIR_0
  B0  = RST_CPU0_DRAM_GH_PLD_N
  B1  = RST_CPU0_DRAM_EF_PLD_N
  VREF  = P0V62_CPU0_RST_DDR_VREF
  B2  = RST_CPU0_DRAM_CD_PLD_N
  B3  = RST_CPU0_DRAM_AB_PLD_N
  GND_0  = GND
  GND_1  = GND
  A3  = RST_CPU0_DRAM_AB_PLD_LVT3_R_N
  A2  = RST_CPU0_DRAM_CD_PLD_LVT3_R_N
  GND_2  = GND
  A1  = RST_CPU0_DRAM_EF_PLD_LVT3_R_N
  A0  = RST_CPU0_DRAM_GH_PLD_LVT3_R_N
  VCC  = P3V3_AUX

(kicad_pcb
	(version 20260206)
	(generator "pcbnew")
	(generator_version "10.0")
	(general
		(thickness 1.6)
		(legacy_teardrops no)
	)
	(paper "A4")
	(title_block
		(title "03242023_DA0F0TMBIJ0_F0T_Motherboard_J_brd_V01_OCP.brd")
		(comment 1 "Grand Teton / footprints 194-195 of 6105")
	)
	(layers
		(0 "F.Cu" signal "TOP")
		(4 "In1.Cu" signal "GND")
		(6 "In2.Cu" signal "IN1")
		(8 "In3.Cu" signal "GND1")
		(10 "In4.Cu" signal "IN2")
		(12 "In5.Cu" signal "GND2")
		(14 "In6.Cu" signal "IN3")
		(16 "In7.Cu" signal "GND3")
		(18 "In8.Cu" signal "VCC")
		(20 "In9.Cu" signal "VCC1")
		(22 "In10.Cu" signal "GND4")
		(24 "In11.Cu" signal "IN4")
		(26 "In12.Cu" signal "GND5")
		(28 "In13.Cu" signal "IN5")
		(30 "In14.Cu" signal "GND6")
		(32 "In15.Cu" signal "IN6")
		(34 "In16.Cu" signal "GND7")
		(2 "B.Cu" signal "BOTTOM")
		(9 "F.Adhes" user "F.Adhesive")
		(11 "B.Adhes" user "B.Adhesive")
		(13 "F.Paste" user "Package Geometry/Pastemask Top")
		(15 "B.Paste" user "Package Geometry/Pastemask Bottom")
		(5 "F.SilkS" user "Ref Des/Silkscreen Top")
		(7 "B.SilkS" user "Ref Des/Silkscreen Bottom")
		(1 "F.Mask" user "Board Geometry/Soldermask Top")
		(3 "B.Mask" user "Board Geometry/Soldermask Bottom")
		(17 "Dwgs.User" user "User.Drawings")
		(19 "Cmts.User" user "User.Comments")
		(21 "Eco1.User" user "User.Eco1")
		(23 "Eco2.User" user "User.Eco2")
		(25 "Edge.Cuts" user "Board Geometry/Outline")
		(27 "Margin" user)
		(31 "F.CrtYd" user "Package Geometry/Place Bound Top")
		(29 "B.CrtYd" user "Package Geometry/Place Bound Bottom")
		(35 "F.Fab" user "Ref Des/Assembly Top")
		(33 "B.Fab" user "Ref Des/Assembly Bottom")
	)
	(footprint ""
		(layer "F.Cu")
		(at 114.660934 -113.157762 -90)
		(property "Reference" "U304"
			(at -0.219456 -2.976626 0)
			(unlocked yes)
			(layer "F.SilkS")
			(effects
				(font
					(size 0.7874 0.5842)
					(thickness 0.1524)
				)
				(justify left)
			)
		)
		(property "Value" ""
			(at 0 0 270)
			(layer "F.Fab")
			(effects
				(font
					(size 1.27 1.27)
				)
			)
		)
		(duplicate_pad_numbers_are_jumpers no)
		(fp_line
			(start -2.0066 2.5527)
			(end -2.0066 -2.5527)
			(stroke
				(width 0.1524)
				(type default)
			)
			(layer "F.SilkS")
		)
		(fp_line
			(start 2.0066 2.5527)
			(end -2.0066 2.5527)
			(stroke
				(width 0.1524)
				(type default)
			)
			(layer "F.SilkS")
		)
		(fp_line
			(start 0 -1.9812)
			(end 0.5715 -2.5527)
			(stroke
				(width 0.1524)
				(type default)
			)
			(layer "F.SilkS")
		)
		(fp_line
			(start -2.0066 -2.5527)
			(end -0.5715 -2.5527)
			(stroke
				(width 0.1524)
				(type default)
			)
			(layer "F.SilkS")
		)
		(fp_line
			(start -0.5715 -2.5527)
			(end 0 -1.9812)
			(stroke
				(width 0.1524)
				(type default)
			)
			(layer "F.SilkS")
		)
		(fp_line
			(start 0.5715 -2.5527)
			(end 2.0066 -2.5527)
			(stroke
				(width 0.1524)
				(type default)
			)
			(layer "F.SilkS")
		)
		(fp_line
			(start 2.0066 -2.5527)
			(end 2.0066 2.5527)
			(stroke
				(width 0.1524)
				(type default)
			)
			(layer "F.SilkS")
		)
		(fp_poly
			(pts
				(xy -4.36372 -2.233168) (xy -3.81 -1.905) (xy -4.36372 -1.608328)
			)
			(stroke
				(width 0)
				(type default)
			)
			(fill yes)
			(layer "F.SilkS")
		)
		(fp_line
			(start -2.249932 2.549906)
			(end -2.249932 -2.549906)
			(stroke
				(width 0.1)
				(type default)
			)
			(layer "F.Fab")
		)
		(fp_line
			(start 2.249932 2.549906)
			(end -2.249932 2.549906)
			(stroke
				(width 0.1)
				(type default)
			)
			(layer "F.Fab")
		)
		(fp_line
			(start -2.249932 -2.549906)
			(end 2.249932 -2.549906)
			(stroke
				(width 0.1)
				(type default)
			)
			(layer "F.Fab")
		)
		(fp_line
			(start 2.249932 -2.549906)
			(end 2.249932 2.549906)
			(stroke
				(width 0.1)
				(type default)
			)
			(layer "F.Fab")
		)
		(fp_poly
			(pts
				(xy -4.36372 -1.608328) (xy -4.36372 -2.233168) (xy -3.81 -1.905)
			)
			(stroke
				(width 0)
				(type default)
			)
			(fill yes)
			(layer "F.Fab")
		)
		(pad "1" smd rect
			(at -2.921 -1.949958 180)
			(size 0.3556 1.4986)
			(layers "F.Cu" "F.Mask" "F.Paste")
			(net "PD_GTL2014_BMC_JTAG_DIR_0")
		)
		(pad "2" smd rect
			(at -2.921 -1.299972 180)
			(size 0.3556 1.4986)
			(layers "F.Cu" "F.Mask" "F.Paste")
			(net "RST_CPU0_DRAM_GH_PLD_N")
		)
		(pad "3" smd rect
			(at -2.921 -0.649986 180)
			(size 0.3556 1.4986)
			(layers "F.Cu" "F.Mask" "F.Paste")
			(net "RST_CPU0_DRAM_EF_PLD_N")
		)
		(pad "4" smd rect
			(at -2.921 0 180)
			(size 0.3556 1.4986)
			(layers "F.Cu" "F.Mask" "F.Paste")
			(net "P0V62_CPU0_RST_DDR_VREF")
		)
		(pad "5" smd rect
			(at -2.921 0.649986 180)
			(size 0.3556 1.4986)
			(layers "F.Cu" "F.Mask" "F.Paste")
			(net "RST_CPU0_DRAM_CD_PLD_N")
		)
		(pad "6" smd rect
			(at -2.921 1.299972 180)
			(size 0.3556 1.4986)
			(layers "F.Cu" "F.Mask" "F.Paste")
			(net "RST_CPU0_DRAM_AB_PLD_N")
		)
		(pad "7" smd rect
			(at -2.921 1.949958 180)
			(size 0.3556 1.4986)
			(layers "F.Cu" "F.Mask" "F.Paste")
			(net "GND")
		)
		(pad "8" smd rect
			(at 2.921 1.949958 180)
			(size 0.3556 1.4986)
			(layers "F.Cu" "F.Mask" "F.Paste")
			(net "GND")
		)
		(pad "9" smd rect
			(at 2.921 1.299972 180)
			(size 0.3556 1.4986)
			(layers "F.Cu" "F.Mask" "F.Paste")
			(net "RST_CPU0_DRAM_AB_PLD_LVT3_R_N")
		)
		(pad "10" smd rect
			(at 2.921 0.649986 180)
			(size 0.3556 1.4986)
			(layers "F.Cu" "F.Mask" "F.Paste")
			(net "RST_CPU0_DRAM_CD_PLD_LVT3_R_N")
		)
		(pad "11" smd rect
			(at 2.921 0 180)
			(size 0.3556 1.4986)
			(layers "F.Cu" "F.Mask" "F.Paste")
			(net "GND")
		)
		(pad "12" smd rect
			(at 2.921 -0.649986 180)
			(size 0.3556 1.4986)
			(layers "F.Cu" "F.Mask" "F.Paste")
			(net "RST_CPU0_DRAM_EF_PLD_LVT3_R_N")
		)
		(pad "13" smd rect
			(at 2.921 -1.299972 180)
			(size 0.3556 1.4986)
			(layers "F.Cu" "F.Mask" "F.Paste")
			(net "RST_CPU0_DRAM_GH_PLD_LVT3_R_N")
		)
		(pad "14" smd rect
			(at 2.921 -1.949958 180)
			(size 0.3556 1.4986)
			(layers "F.Cu" "F.Mask" "F.Paste")
			(net "P3V3_AUX")
		)
	)
	(footprint ""
		(layer "F.Cu")
		(at 461.593946 -107.043728)
		(property "Reference" "C592"
			(at 0 0 0)
			(layer "F.SilkS")
			(hide yes)
			(effects
				(font
					(size 1.27 1.27)
				)
			)
		)
		(property "Value" ""
			(at 0 0 0)
			(layer "F.Fab")
			(effects
				(font
					(size 1.27 1.27)
				)
			)
		)
		(duplicate_pad_numbers_are_jumpers no)
		(fp_line
			(start -0.7874 -0.4064)
			(end 0.7874 -0.4064)
			(stroke
				(width 0.1524)
				(type default)
			)
			(layer "F.SilkS")
		)
		(fp_line
			(start -0.7874 0.4064)
			(end -0.7874 -0.4064)
			(stroke
				(width 0.1524)
				(type default)
			)
			(layer "F.SilkS")
		)
		(fp_line
			(start 0.7874 -0.4064)
			(end 0.7874 0.4064)
			(stroke
				(width 0.1524)
				(type default)
			)
			(layer "F.SilkS")
		)
		(fp_line
			(start 0.7874 0.4064)
			(end -0.7874 0.4064)
			(stroke
				(width 0.1524)
				(type default)
			)
			(layer "F.SilkS")
		)
		(fp_line
			(start -0.67945 -0.305054)
			(end -0.12065 -0.305054)
			(stroke
				(width 0.1)
				(type default)
			)
			(layer "F.Fab")
		)
		(fp_line
			(start -0.67945 0.3048)
			(end -0.67945 -0.305054)
			(stroke
				(width 0.1)
				(type default)
			)
			(layer "F.Fab")
		)
		(fp_line
			(start -0.12065 -0.305054)
			(end -0.12065 -0.2794)
			(stroke
				(width 0.1)
				(type default)
			)
			(layer "F.Fab")
		)
		(fp_line
			(start -0.12065 -0.2794)
			(end 0.12065 -0.2794)
			(stroke
				(width 0.1)
				(type default)
			)
			(layer "F.Fab")
		)
		(fp_line
			(start -0.12065 0.2794)
			(end -0.12065 0.3048)
			(stroke
				(width 0.1)
				(type default)
			)
			(layer "F.Fab")
		)
		(fp_line
			(start -0.12065 0.3048)
			(end -0.67945 0.3048)
			(stroke
				(width 0.1)
				(type default)
			)
			(layer "F.Fab")
		)
		(fp_line
			(start 0.120396 0.2794)
			(end -0.12065 0.2794)
			(stroke
				(width 0.1)
				(type default)
			)
			(layer "F.Fab")
		)
		(fp_line
			(start 0.120396 0.3048)
			(end 0.120396 0.2794)
			(stroke
				(width 0.1)
				(type default)
			)
			(layer "F.Fab")
		)
		(fp_line
			(start 0.12065 -0.3048)
			(end 0.67945 -0.3048)
			(stroke
				(width 0.1)
				(type default)
			)
			(layer "F.Fab")
		)
		(fp_line
			(start 0.12065 -0.2794)
			(end 0.12065 -0.3048)
			(stroke
				(width 0.1)
				(type default)
			)
			(layer "F.Fab")
		)
		(fp_line
			(start 0.67945 -0.3048)
			(end 0.67945 0.3048)
			(stroke
				(width 0.1)
				(type default)
			)
			(layer "F.Fab")
		)
		(fp_line
			(start 0.67945 0.3048)
			(end 0.120396 0.3048)
			(stroke
				(width 0.1)
				(type default)
			)
			(layer "F.Fab")
		)
		(pad "1" smd circle
			(at -0.40005 0)
			(size 0 0)
			(layers "F.Cu" "F.Mask" "F.Paste")
			(net "P3V3_AUX")
		)
		(pad "2" smd circle
			(at 0.40005 0)
			(size 0 0)
			(layers "F.Cu" "F.Mask" "F.Paste")
			(net "GND")
		)
	)
)
